# S9S_MB_2U (Grand Teton) — schematic netlist excerpt (pin names and nets, part order shuffled) for the footprints in the layout excerpt that follows; sources: Cadence DE-HDL packaged netlist, KiCad conversion of 03242023_DA0F0TMBIJ0_F0T_Motherboard_J_brd_V01_OCP.brd

FS1  Q_FUSE  20A/125V IC  pkg SMLF  page 304 : \1\ = P12V_PSU ; \2\ = P12V_PSU_FUSE
R2212  Q_RES  2.2K 5% EMPTY  pkg 0402LF  page 241 : A = SMB_S3M_CPU_3V3AUX_SCL ; B = P3V3_AUX
PC623  Q_CAPP  330UF 2.5V +10/-35% SPCAP  pkg SMLF  page 271 : A = PVCCFA_EHV_FIVRA_CPU0 ; B = GND

(kicad_pcb
	(version 20260206)
	(generator "pcbnew")
	(generator_version "10.0")
	(general
		(thickness 1.6)
		(legacy_teardrops no)
	)
	(paper "A4")
	(title_block
		(title "03242023_DA0F0TMBIJ0_F0T_Motherboard_J_brd_V01_OCP.brd")
		(comment 1 "Grand Teton / footprints 4808-4810 of 6105")
	)
	(layers
		(0 "F.Cu" signal "TOP")
		(4 "In1.Cu" signal "GND")
		(6 "In2.Cu" signal "IN1")
		(8 "In3.Cu" signal "GND1")
		(10 "In4.Cu" signal "IN2")
		(12 "In5.Cu" signal "GND2")
		(14 "In6.Cu" signal "IN3")
		(16 "In7.Cu" signal "GND3")
		(18 "In8.Cu" signal "VCC")
		(20 "In9.Cu" signal "VCC1")
		(22 "In10.Cu" signal "GND4")
		(24 "In11.Cu" signal "IN4")
		(26 "In12.Cu" signal "GND5")
		(28 "In13.Cu" signal "IN5")
		(30 "In14.Cu" signal "GND6")
		(32 "In15.Cu" signal "IN6")
		(34 "In16.Cu" signal "GND7")
		(2 "B.Cu" signal "BOTTOM")
		(9 "F.Adhes" user "F.Adhesive")
		(11 "B.Adhes" user "B.Adhesive")
		(13 "F.Paste" user "Package Geometry/Pastemask Top")
		(15 "B.Paste" user "Package Geometry/Pastemask Bottom")
		(5 "F.SilkS" user "Ref Des/Silkscreen Top")
		(7 "B.SilkS" user "Ref Des/Silkscreen Bottom")
		(1 "F.Mask" user "Board Geometry/Soldermask Top")
		(3 "B.Mask" user "Board Geometry/Soldermask Bottom")
		(17 "Dwgs.User" user "User.Drawings")
		(19 "Cmts.User" user "User.Comments")
		(21 "Eco1.User" user "User.Eco1")
		(23 "Eco2.User" user "User.Eco2")
		(25 "Edge.Cuts" user "Board Geometry/Outline")
		(27 "Margin" user)
		(31 "F.CrtYd" user "Package Geometry/Place Bound Top")
		(29 "B.CrtYd" user "Package Geometry/Place Bound Bottom")
		(35 "F.Fab" user "Ref Des/Assembly Top")
		(33 "B.Fab" user "Ref Des/Assembly Bottom")
	)
	(footprint ""
		(layer "B.Cu")
		(at 288.746946 -356.036372 -90)
		(property "Reference" "PC623"
			(at 0 0 90)
			(layer "B.SilkS")
			(hide yes)
			(effects
				(font
					(size 1.27 1.27)
				)
				(justify mirror)
			)
		)
		(property "Value" ""
			(at 0 0 90)
			(layer "B.Fab")
			(effects
				(font
					(size 1.27 1.27)
				)
				(justify mirror)
			)
		)
		(duplicate_pad_numbers_are_jumpers no)
		(fp_line
			(start -4.533392 2.249932)
			(end 4.533392 2.249932)
			(stroke
				(width 0.1524)
				(type default)
			)
			(layer "B.SilkS")
		)
		(fp_line
			(start 4.533392 2.249932)
			(end 4.533392 -2.249932)
			(stroke
				(width 0.1524)
				(type default)
			)
			(layer "B.SilkS")
		)
		(fp_line
			(start -4.533392 -2.249932)
			(end -4.533392 2.249932)
			(stroke
				(width 0.1524)
				(type default)
			)
			(layer "B.SilkS")
		)
		(fp_line
			(start 4.533392 -2.249932)
			(end -4.533392 -2.249932)
			(stroke
				(width 0.1524)
				(type default)
			)
			(layer "B.SilkS")
		)
		(fp_poly
			(pts
				(xy 4.533392 -2.326132) (xy 5.39242 -2.326132) (xy 5.39242 2.326132) (xy 4.533392 2.326132)
			)
			(stroke
				(width 0)
				(type default)
			)
			(fill yes)
			(layer "B.SilkS")
		)
		(fp_line
			(start -3.750056 2.249932)
			(end 3.750056 2.249932)
			(stroke
				(width 0.1)
				(type default)
			)
			(layer "B.Fab")
		)
		(fp_line
			(start 3.750056 2.249932)
			(end 3.750056 -2.249932)
			(stroke
				(width 0.1)
				(type default)
			)
			(layer "B.Fab")
		)
		(fp_line
			(start -3.750056 -2.249932)
			(end -3.750056 2.249932)
			(stroke
				(width 0.1)
				(type default)
			)
			(layer "B.Fab")
		)
		(fp_line
			(start 3.750056 -2.249932)
			(end -3.750056 -2.249932)
			(stroke
				(width 0.1)
				(type default)
			)
			(layer "B.Fab")
		)
		(fp_text user "+"
			(at 6.322314 0.786384 180)
			(unlocked yes)
			(layer "B.SilkS")
			(effects
				(font
					(size 1.905 1.4224)
					(thickness 0.1524)
				)
				(justify left mirror)
			)
		)
		(fp_text user "-"
			(at -4.8514 -0.14605 270)
			(unlocked yes)
			(layer "B.SilkS")
			(effects
				(font
					(size 1.905 1.4224)
					(thickness 0.1524)
				)
				(justify left mirror)
			)
		)
		(fp_text user "+"
			(at 6.322314 0.786384 180)
			(unlocked yes)
			(layer "B.Fab")
			(effects
				(font
					(size 1.905 1.4224)
					(thickness 0.1524)
				)
				(justify left mirror)
			)
		)
		(fp_text user "-"
			(at -4.8514 -0.14605 270)
			(unlocked yes)
			(layer "B.Fab")
			(effects
				(font
					(size 1.905 1.4224)
					(thickness 0.1524)
				)
				(justify left mirror)
			)
		)
		(pad "1" smd rect
			(at 3.199892 0 90)
			(size 2.413 2.8194)
			(layers "B.Cu" "B.Mask" "B.Paste")
			(net "PVCCFA_EHV_FIVRA_CPU0")
		)
		(pad "2" smd rect
			(at -3.199892 0 90)
			(size 2.413 2.8194)
			(layers "B.Cu" "B.Mask" "B.Paste")
			(net "GND")
		)
	)
	(footprint ""
		(layer "B.Cu")
		(at 151.69388 -22.824948 -90)
		(property "Reference" "R2212"
			(at 0 0 90)
			(layer "B.SilkS")
			(hide yes)
			(effects
				(font
					(size 1.27 1.27)
				)
				(justify mirror)
			)
		)
		(property "Value" ""
			(at 0 0 90)
			(layer "B.Fab")
			(effects
				(font
					(size 1.27 1.27)
				)
				(justify mirror)
			)
		)
		(duplicate_pad_numbers_are_jumpers no)
		(fp_line
			(start -0.7874 0.4064)
			(end 0.7874 0.4064)
			(stroke
				(width 0.1524)
				(type default)
			)
			(layer "B.SilkS")
		)
		(fp_line
			(start 0.7874 0.4064)
			(end 0.7874 -0.4064)
			(stroke
				(width 0.1524)
				(type default)
			)
			(layer "B.SilkS")
		)
		(fp_line
			(start -0.7874 -0.4064)
			(end -0.7874 0.4064)
			(stroke
				(width 0.1524)
				(type default)
			)
			(layer "B.SilkS")
		)
		(fp_line
			(start 0.7874 -0.4064)
			(end -0.7874 -0.4064)
			(stroke
				(width 0.1524)
				(type default)
			)
			(layer "B.SilkS")
		)
		(fp_line
			(start -0.67945 0.3048)
			(end -0.120396 0.3048)
			(stroke
				(width 0.1)
				(type default)
			)
			(layer "B.Fab")
		)
		(fp_line
			(start -0.120396 0.3048)
			(end -0.120396 0.2794)
			(stroke
				(width 0.1)
				(type default)
			)
			(layer "B.Fab")
		)
		(fp_line
			(start 0.12065 0.3048)
			(end 0.67945 0.3048)
			(stroke
				(width 0.1)
				(type default)
			)
			(layer "B.Fab")
		)
		(fp_line
			(start 0.67945 0.3048)
			(end 0.67945 -0.305054)
			(stroke
				(width 0.1)
				(type default)
			)
			(layer "B.Fab")
		)
		(fp_line
			(start -0.120396 0.2794)
			(end 0.12065 0.2794)
			(stroke
				(width 0.1)
				(type default)
			)
			(layer "B.Fab")
		)
		(fp_line
			(start 0.12065 0.2794)
			(end 0.12065 0.3048)
			(stroke
				(width 0.1)
				(type default)
			)
			(layer "B.Fab")
		)
		(fp_line
			(start -0.12065 -0.2794)
			(end -0.12065 -0.3048)
			(stroke
				(width 0.1)
				(type default)
			)
			(layer "B.Fab")
		)
		(fp_line
			(start 0.12065 -0.2794)
			(end -0.12065 -0.2794)
			(stroke
				(width 0.1)
				(type default)
			)
			(layer "B.Fab")
		)
		(fp_line
			(start -0.67945 -0.3048)
			(end -0.67945 0.3048)
			(stroke
				(width 0.1)
				(type default)
			)
			(layer "B.Fab")
		)
		(fp_line
			(start -0.12065 -0.3048)
			(end -0.67945 -0.3048)
			(stroke
				(width 0.1)
				(type default)
			)
			(layer "B.Fab")
		)
		(fp_line
			(start 0.12065 -0.305054)
			(end 0.12065 -0.2794)
			(stroke
				(width 0.1)
				(type default)
			)
			(layer "B.Fab")
		)
		(fp_line
			(start 0.67945 -0.305054)
			(end 0.12065 -0.305054)
			(stroke
				(width 0.1)
				(type default)
			)
			(layer "B.Fab")
		)
		(pad "1" smd circle
			(at 0.40005 0 90)
			(size 0 0)
			(layers "B.Cu" "B.Mask" "B.Paste")
			(net "SMB_S3M_CPU_3V3AUX_SCL")
		)
		(pad "2" smd circle
			(at -0.40005 0 90)
			(size 0 0)
			(layers "B.Cu" "B.Mask" "B.Paste")
			(net "P3V3_AUX")
		)
	)
	(footprint ""
		(layer "B.Cu")
		(at 245.58752 -418.05098 180)
		(property "Reference" "FS1"
			(at 6.7183 -2.619248 180)
			(unlocked yes)
			(layer "B.SilkS")
			(effects
				(font
					(size 0.7874 0.5842)
					(thickness 0.1524)
				)
				(justify left mirror)
			)
		)
		(property "Value" ""
			(at 0 0 0)
			(layer "B.Fab")
			(effects
				(font
					(size 1.27 1.27)
				)
				(justify mirror)
			)
		)
		(duplicate_pad_numbers_are_jumpers no)
		(fp_line
			(start 6.427724 1.8415)
			(end -6.427724 1.8415)
			(stroke
				(width 0.1524)
				(type default)
			)
			(layer "B.SilkS")
		)
		(fp_line
			(start 6.427724 -1.8415)
			(end 6.427724 1.8415)
			(stroke
				(width 0.1524)
				(type default)
			)
			(layer "B.SilkS")
		)
		(fp_line
			(start -6.427724 1.8415)
			(end -6.427724 -1.8415)
			(stroke
				(width 0.1524)
				(type default)
			)
			(layer "B.SilkS")
		)
		(fp_line
			(start -6.427724 -1.8415)
			(end 6.427724 -1.8415)
			(stroke
				(width 0.1524)
				(type default)
			)
			(layer "B.SilkS")
		)
		(fp_line
			(start 5.050028 1.560068)
			(end -5.050028 1.560068)
			(stroke
				(width 0.1)
				(type default)
			)
			(layer "B.Fab")
		)
		(fp_line
			(start 5.050028 -1.560068)
			(end 5.050028 1.560068)
			(stroke
				(width 0.1)
				(type default)
			)
			(layer "B.Fab")
		)
		(fp_line
			(start -5.050028 1.560068)
			(end -5.050028 -1.560068)
			(stroke
				(width 0.1)
				(type default)
			)
			(layer "B.Fab")
		)
		(fp_line
			(start -5.050028 -1.560068)
			(end 5.050028 -1.560068)
			(stroke
				(width 0.1)
				(type default)
			)
			(layer "B.Fab")
		)
		(pad "1" smd rect
			(at 4.675124 0)
			(size 3.2512 3.429)
			(layers "B.Cu" "B.Mask" "B.Paste")
			(net "P12V_PSU")
		)
		(pad "2" smd rect
			(at -4.675124 0)
			(size 3.2512 3.429)
			(layers "B.Cu" "B.Mask" "B.Paste")
			(net "P12V_PSU_FUSE")
		)
	)
)
